(kicad_pcb
	(version 20260206)
	(generator "pcbnew")
	(generator_version "10.0")
	(general
		(thickness 1.6)
		(legacy_teardrops no)
	)
	(paper "A4")
	(title_block
		(title "01162023_DA0F0TEBIF0_F0T_Expander_BD_F_brd_V02_OCP.brd")
		(comment 1 "Grand Teton / footprint 4451 of 9728 (PEX3), pads 1075-1189 of 2397")
	)
	(layers
		(0 "F.Cu" signal "TOP")
		(4 "In1.Cu" signal "GND")
		(6 "In2.Cu" signal "VCC")
		(8 "In3.Cu" signal "VCC1")
		(10 "In4.Cu" signal "GND1")
		(12 "In5.Cu" signal "IN1")
		(14 "In6.Cu" signal "GND2")
		(16 "In7.Cu" signal "IN2")
		(18 "In8.Cu" signal "GND3")
		(20 "In9.Cu" signal "IN3")
		(22 "In10.Cu" signal "GND4")
		(24 "In11.Cu" signal "IN4")
		(26 "In12.Cu" signal "GND5")
		(28 "In13.Cu" signal "IN5")
		(30 "In14.Cu" signal "GND6")
		(32 "In15.Cu" signal "IN6")
		(34 "In16.Cu" signal "GND7")
		(2 "B.Cu" signal "BOTTOM")
		(9 "F.Adhes" user "F.Adhesive")
		(11 "B.Adhes" user "B.Adhesive")
		(13 "F.Paste" user "Package Geometry/Pastemask Top")
		(15 "B.Paste" user "Package Geometry/Pastemask Bottom")
		(5 "F.SilkS" user "Ref Des/Silkscreen Top")
		(7 "B.SilkS" user "Ref Des/Silkscreen Bottom")
		(1 "F.Mask" user "Board Geometry/Soldermask Top")
		(3 "B.Mask" user "Board Geometry/Soldermask Bottom")
		(17 "Dwgs.User" user "User.Drawings")
		(19 "Cmts.User" user "User.Comments")
		(21 "Eco1.User" user "User.Eco1")
		(23 "Eco2.User" user "User.Eco2")
		(25 "Edge.Cuts" user "Board Geometry/Outline")
		(27 "Margin" user)
		(31 "F.CrtYd" user "Package Geometry/Place Bound Top")
		(29 "B.CrtYd" user "Package Geometry/Place Bound Bottom")
		(35 "F.Fab" user "Ref Des/Assembly Top")
		(33 "B.Fab" user "Ref Des/Assembly Bottom")
	)
	(footprint ""
		(layer "F.Cu")
		(at 407.949908 -295.89984)
		(property "Reference" "PEX3"
			(at -3.358642 35.5727 0)
			(unlocked yes)
			(layer "F.SilkS")
			(effects
				(font
					(size 2.032 1.524)
					(thickness 0.1524)
				)
				(justify left)
			)
		)
		(property "Value" ""
			(at 0 0 0)
			(layer "F.Fab")
			(effects
				(font
					(size 1.27 1.27)
				)
			)
		)
		(duplicate_pad_numbers_are_jumpers no)
		(pad "B48" smd circle
			(at 21.850096 -21.850096)
			(size 0.4572 0.4572)
			(layers "F.Cu" "F.Mask" "F.Paste")
			(net "GND")
		)
		(pad "B49" smd circle
			(at 22.800056 -21.850096)
			(size 0.4572 0.4572)
			(layers "F.Cu" "F.Mask" "F.Paste")
			(net "GND")
		)
		(pad "BA1" smd circle
			(at -22.800056 15.200122)
			(size 0.4572 0.4572)
			(layers "F.Cu" "F.Mask" "F.Paste")
			(net "GND")
		)
		(pad "BA2" smd circle
			(at -21.850096 15.200122)
			(size 0.4572 0.4572)
			(layers "F.Cu" "F.Mask" "F.Paste")
			(net "GND")
		)
		(pad "BA3" smd circle
			(at -20.899882 15.200122)
			(size 0.4572 0.4572)
			(layers "F.Cu" "F.Mask" "F.Paste")
			(net "GND")
		)
		(pad "BA4" smd circle
			(at -19.949922 15.200122)
			(size 0.4572 0.4572)
			(layers "F.Cu" "F.Mask" "F.Paste")
			(net "Net_1450")
		)
		(pad "BA5" smd circle
			(at -18.999962 15.200122)
			(size 0.4572 0.4572)
			(layers "F.Cu" "F.Mask" "F.Paste")
			(net "GND")
		)
		(pad "BA6" smd circle
			(at -18.050002 15.200122)
			(size 0.4572 0.4572)
			(layers "F.Cu" "F.Mask" "F.Paste")
			(net "Net_1361")
		)
		(pad "BA7" smd circle
			(at -17.100042 15.200122)
			(size 0.4572 0.4572)
			(layers "F.Cu" "F.Mask" "F.Paste")
			(net "GND")
		)
		(pad "BA8" smd circle
			(at -16.150082 15.200122)
			(size 0.4572 0.4572)
			(layers "F.Cu" "F.Mask" "F.Paste")
			(net "Net_1440")
		)
		(pad "BA9" smd circle
			(at -15.200122 15.200122)
			(size 0.4572 0.4572)
			(layers "F.Cu" "F.Mask" "F.Paste")
			(net "GND")
		)
		(pad "BA10" smd circle
			(at -14.249908 15.200122)
			(size 0.4572 0.4572)
			(layers "F.Cu" "F.Mask" "F.Paste")
			(net "P5E_PEX3_STN2_TX_DP<46>")
		)
		(pad "BA11" smd circle
			(at -13.299948 15.200122)
			(size 0.4572 0.4572)
			(layers "F.Cu" "F.Mask" "F.Paste")
			(net "GND")
		)
		(pad "BA12" smd circle
			(at -12.349988 15.200122)
			(size 0.4572 0.4572)
			(layers "F.Cu" "F.Mask" "F.Paste")
			(net "P5E_PEX3_STN2_TX_DP<44>")
		)
		(pad "BA13" smd circle
			(at -11.400028 15.200122)
			(size 0.4572 0.4572)
			(layers "F.Cu" "F.Mask" "F.Paste")
			(net "GND")
		)
		(pad "BA14" smd circle
			(at -10.450068 15.200122)
			(size 0.4572 0.4572)
			(layers "F.Cu" "F.Mask" "F.Paste")
			(net "P5E_PEX3_STN2_TX_DP<42>")
		)
		(pad "BA15" smd circle
			(at -9.500108 15.200122)
			(size 0.4572 0.4572)
			(layers "F.Cu" "F.Mask" "F.Paste")
			(net "GND")
		)
		(pad "BA16" smd circle
			(at -8.549894 15.200122)
			(size 0.4572 0.4572)
			(layers "F.Cu" "F.Mask" "F.Paste")
			(net "P5E_PEX3_STN2_TX_DP<40>")
		)
		(pad "BA17" smd circle
			(at -7.599934 15.200122)
			(size 0.4572 0.4572)
			(layers "F.Cu" "F.Mask" "F.Paste")
			(net "GND")
		)
		(pad "BA18" smd circle
			(at -6.649974 15.200122)
			(size 0.4572 0.4572)
			(layers "F.Cu" "F.Mask" "F.Paste")
			(net "P5E_PEX3_STN2_TX_DP<38>")
		)
		(pad "BA19" smd circle
			(at -5.700014 15.200122)
			(size 0.4572 0.4572)
			(layers "F.Cu" "F.Mask" "F.Paste")
			(net "GND")
		)
		(pad "BA20" smd circle
			(at -4.750054 15.200122)
			(size 0.4572 0.4572)
			(layers "F.Cu" "F.Mask" "F.Paste")
			(net "P5E_PEX3_STN2_TX_DP<36>")
		)
		(pad "BA21" smd circle
			(at -3.800094 15.200122)
			(size 0.4572 0.4572)
			(layers "F.Cu" "F.Mask" "F.Paste")
			(net "GND")
		)
		(pad "BA22" smd circle
			(at -2.84988 15.200122)
			(size 0.4572 0.4572)
			(layers "F.Cu" "F.Mask" "F.Paste")
			(net "P5E_PEX3_STN2_TX_DP<34>")
		)
		(pad "BA23" smd circle
			(at -1.89992 15.200122)
			(size 0.4572 0.4572)
			(layers "F.Cu" "F.Mask" "F.Paste")
			(net "GND")
		)
		(pad "BA24" smd circle
			(at -0.94996 15.200122)
			(size 0.4572 0.4572)
			(layers "F.Cu" "F.Mask" "F.Paste")
			(net "P5E_PEX3_STN2_TX_DP<32>")
		)
		(pad "BA25" smd circle
			(at 0 15.200122)
			(size 0.4572 0.4572)
			(layers "F.Cu" "F.Mask" "F.Paste")
			(net "GND")
		)
		(pad "BA26" smd circle
			(at 0.94996 15.200122)
			(size 0.4572 0.4572)
			(layers "F.Cu" "F.Mask" "F.Paste")
			(net "P5E_PEX3_STN1_TX_DN<17>")
		)
		(pad "BA27" smd circle
			(at 1.89992 15.200122)
			(size 0.4572 0.4572)
			(layers "F.Cu" "F.Mask" "F.Paste")
			(net "GND")
		)
		(pad "BA28" smd circle
			(at 2.84988 15.200122)
			(size 0.4572 0.4572)
			(layers "F.Cu" "F.Mask" "F.Paste")
			(net "P5E_PEX3_STN1_TX_DN<19>")
		)
		(pad "BA29" smd circle
			(at 3.800094 15.200122)
			(size 0.4572 0.4572)
			(layers "F.Cu" "F.Mask" "F.Paste")
			(net "GND")
		)
		(pad "BA30" smd circle
			(at 4.750054 15.200122)
			(size 0.4572 0.4572)
			(layers "F.Cu" "F.Mask" "F.Paste")
			(net "P5E_PEX3_STN1_TX_DN<21>")
		)
		(pad "BA31" smd circle
			(at 5.700014 15.200122)
			(size 0.4572 0.4572)
			(layers "F.Cu" "F.Mask" "F.Paste")
			(net "GND")
		)
		(pad "BA32" smd circle
			(at 6.649974 15.200122)
			(size 0.4572 0.4572)
			(layers "F.Cu" "F.Mask" "F.Paste")
			(net "P5E_PEX3_STN1_TX_DN<23>")
		)
		(pad "BA33" smd circle
			(at 7.599934 15.200122)
			(size 0.4572 0.4572)
			(layers "F.Cu" "F.Mask" "F.Paste")
			(net "GND")
		)
		(pad "BA34" smd circle
			(at 8.549894 15.200122)
			(size 0.4572 0.4572)
			(layers "F.Cu" "F.Mask" "F.Paste")
			(net "P5E_PEX3_STN1_TX_DN<25>")
		)
		(pad "BA35" smd circle
			(at 9.500108 15.200122)
			(size 0.4572 0.4572)
			(layers "F.Cu" "F.Mask" "F.Paste")
			(net "GND")
		)
		(pad "BA36" smd circle
			(at 10.450068 15.200122)
			(size 0.4572 0.4572)
			(layers "F.Cu" "F.Mask" "F.Paste")
			(net "P5E_PEX3_STN1_TX_DN<27>")
		)
		(pad "BA37" smd circle
			(at 11.400028 15.200122)
			(size 0.4572 0.4572)
			(layers "F.Cu" "F.Mask" "F.Paste")
			(net "GND")
		)
		(pad "BA38" smd circle
			(at 12.349988 15.200122)
			(size 0.4572 0.4572)
			(layers "F.Cu" "F.Mask" "F.Paste")
			(net "P5E_PEX3_STN1_TX_DN<29>")
		)
		(pad "BA39" smd circle
			(at 13.299948 15.200122)
			(size 0.4572 0.4572)
			(layers "F.Cu" "F.Mask" "F.Paste")
			(net "GND")
		)
		(pad "BA40" smd circle
			(at 14.249908 15.200122)
			(size 0.4572 0.4572)
			(layers "F.Cu" "F.Mask" "F.Paste")
			(net "P5E_PEX3_STN1_TX_DN<31>")
		)
		(pad "BA41" smd circle
			(at 15.200122 15.200122)
			(size 0.4572 0.4572)
			(layers "F.Cu" "F.Mask" "F.Paste")
			(net "GND")
		)
		(pad "BA42" smd circle
			(at 16.150082 15.200122)
			(size 0.4572 0.4572)
			(layers "F.Cu" "F.Mask" "F.Paste")
			(net "P5E_PEX3_STN0_TX_DN<14>")
		)
		(pad "BA43" smd circle
			(at 17.100042 15.200122)
			(size 0.4572 0.4572)
			(layers "F.Cu" "F.Mask" "F.Paste")
			(net "GND")
		)
		(pad "BA44" smd circle
			(at 18.050002 15.200122)
			(size 0.4572 0.4572)
			(layers "F.Cu" "F.Mask" "F.Paste")
			(net "P5E_PEX3_STN0_TX_DN<12>")
		)
		(pad "BA45" smd circle
			(at 18.999962 15.200122)
			(size 0.4572 0.4572)
			(layers "F.Cu" "F.Mask" "F.Paste")
			(net "GND")
		)
		(pad "BA46" smd circle
			(at 19.949922 15.200122)
			(size 0.4572 0.4572)
			(layers "F.Cu" "F.Mask" "F.Paste")
			(net "P5E_PEX3_STN0_TX_DP<10>")
		)
		(pad "BA47" smd circle
			(at 20.899882 15.200122)
			(size 0.4572 0.4572)
			(layers "F.Cu" "F.Mask" "F.Paste")
			(net "GND")
		)
		(pad "BA48" smd circle
			(at 21.850096 15.200122)
			(size 0.4572 0.4572)
			(layers "F.Cu" "F.Mask" "F.Paste")
			(net "GND")
		)
		(pad "BA49" smd circle
			(at 22.800056 15.200122)
			(size 0.4572 0.4572)
			(layers "F.Cu" "F.Mask" "F.Paste")
			(net "GND")
		)
		(pad "BB1" smd circle
			(at -22.800056 16.150082)
			(size 0.4572 0.4572)
			(layers "F.Cu" "F.Mask" "F.Paste")
			(net "Net_1728")
		)
		(pad "BB2" smd circle
			(at -21.850096 16.150082)
			(size 0.4572 0.4572)
			(layers "F.Cu" "F.Mask" "F.Paste")
			(net "Net_1469")
		)
		(pad "BB3" smd circle
			(at -20.899882 16.150082)
			(size 0.4572 0.4572)
			(layers "F.Cu" "F.Mask" "F.Paste")
			(net "GND")
		)
		(pad "BB4" smd circle
			(at -19.949922 16.150082)
			(size 0.4572 0.4572)
			(layers "F.Cu" "F.Mask" "F.Paste")
			(net "Net_1458")
		)
		(pad "BB5" smd circle
			(at -18.999962 16.150082)
			(size 0.4572 0.4572)
			(layers "F.Cu" "F.Mask" "F.Paste")
			(net "GND")
		)
		(pad "BB6" smd circle
			(at -18.050002 16.150082)
			(size 0.4572 0.4572)
			(layers "F.Cu" "F.Mask" "F.Paste")
			(net "Net_1446")
		)
		(pad "BB7" smd circle
			(at -17.100042 16.150082)
			(size 0.4572 0.4572)
			(layers "F.Cu" "F.Mask" "F.Paste")
			(net "GND")
		)
		(pad "BB8" smd circle
			(at -16.150082 16.150082)
			(size 0.4572 0.4572)
			(layers "F.Cu" "F.Mask" "F.Paste")
			(net "Net_1412")
		)
		(pad "BB9" smd circle
			(at -15.200122 16.150082)
			(size 0.4572 0.4572)
			(layers "F.Cu" "F.Mask" "F.Paste")
			(net "GND")
		)
		(pad "BB10" smd circle
			(at -14.249908 16.150082)
			(size 0.4572 0.4572)
			(layers "F.Cu" "F.Mask" "F.Paste")
			(net "P5E_PEX3_STN2_TX_DN<46>")
		)
		(pad "BB11" smd circle
			(at -13.299948 16.150082)
			(size 0.4572 0.4572)
			(layers "F.Cu" "F.Mask" "F.Paste")
			(net "GND")
		)
		(pad "BB12" smd circle
			(at -12.349988 16.150082)
			(size 0.4572 0.4572)
			(layers "F.Cu" "F.Mask" "F.Paste")
			(net "P5E_PEX3_STN2_TX_DN<44>")
		)
		(pad "BB13" smd circle
			(at -11.400028 16.150082)
			(size 0.4572 0.4572)
			(layers "F.Cu" "F.Mask" "F.Paste")
			(net "GND")
		)
		(pad "BB14" smd circle
			(at -10.450068 16.150082)
			(size 0.4572 0.4572)
			(layers "F.Cu" "F.Mask" "F.Paste")
			(net "P5E_PEX3_STN2_TX_DN<42>")
		)
		(pad "BB15" smd circle
			(at -9.500108 16.150082)
			(size 0.4572 0.4572)
			(layers "F.Cu" "F.Mask" "F.Paste")
			(net "GND")
		)
		(pad "BB16" smd circle
			(at -8.549894 16.150082)
			(size 0.4572 0.4572)
			(layers "F.Cu" "F.Mask" "F.Paste")
			(net "P5E_PEX3_STN2_TX_DN<40>")
		)
		(pad "BB17" smd circle
			(at -7.599934 16.150082)
			(size 0.4572 0.4572)
			(layers "F.Cu" "F.Mask" "F.Paste")
			(net "GND")
		)
		(pad "BB18" smd circle
			(at -6.649974 16.150082)
			(size 0.4572 0.4572)
			(layers "F.Cu" "F.Mask" "F.Paste")
			(net "P5E_PEX3_STN2_TX_DN<38>")
		)
		(pad "BB19" smd circle
			(at -5.700014 16.150082)
			(size 0.4572 0.4572)
			(layers "F.Cu" "F.Mask" "F.Paste")
			(net "GND")
		)
		(pad "BB20" smd circle
			(at -4.750054 16.150082)
			(size 0.4572 0.4572)
			(layers "F.Cu" "F.Mask" "F.Paste")
			(net "P5E_PEX3_STN2_TX_DN<36>")
		)
		(pad "BB21" smd circle
			(at -3.800094 16.150082)
			(size 0.4572 0.4572)
			(layers "F.Cu" "F.Mask" "F.Paste")
			(net "GND")
		)
		(pad "BB22" smd circle
			(at -2.84988 16.150082)
			(size 0.4572 0.4572)
			(layers "F.Cu" "F.Mask" "F.Paste")
			(net "P5E_PEX3_STN2_TX_DN<34>")
		)
		(pad "BB23" smd circle
			(at -1.89992 16.150082)
			(size 0.4572 0.4572)
			(layers "F.Cu" "F.Mask" "F.Paste")
			(net "GND")
		)
		(pad "BB24" smd circle
			(at -0.94996 16.150082)
			(size 0.4572 0.4572)
			(layers "F.Cu" "F.Mask" "F.Paste")
			(net "P5E_PEX3_STN2_TX_DN<32>")
		)
		(pad "BB25" smd circle
			(at 0 16.150082)
			(size 0.4572 0.4572)
			(layers "F.Cu" "F.Mask" "F.Paste")
			(net "GND")
		)
		(pad "BB26" smd circle
			(at 0.94996 16.150082)
			(size 0.4572 0.4572)
			(layers "F.Cu" "F.Mask" "F.Paste")
			(net "P5E_PEX3_STN1_TX_DP<17>")
		)
		(pad "BB27" smd circle
			(at 1.89992 16.150082)
			(size 0.4572 0.4572)
			(layers "F.Cu" "F.Mask" "F.Paste")
			(net "GND")
		)
		(pad "BB28" smd circle
			(at 2.84988 16.150082)
			(size 0.4572 0.4572)
			(layers "F.Cu" "F.Mask" "F.Paste")
			(net "P5E_PEX3_STN1_TX_DP<19>")
		)
		(pad "BB29" smd circle
			(at 3.800094 16.150082)
			(size 0.4572 0.4572)
			(layers "F.Cu" "F.Mask" "F.Paste")
			(net "GND")
		)
		(pad "BB30" smd circle
			(at 4.750054 16.150082)
			(size 0.4572 0.4572)
			(layers "F.Cu" "F.Mask" "F.Paste")
			(net "P5E_PEX3_STN1_TX_DP<21>")
		)
		(pad "BB31" smd circle
			(at 5.700014 16.150082)
			(size 0.4572 0.4572)
			(layers "F.Cu" "F.Mask" "F.Paste")
			(net "GND")
		)
		(pad "BB32" smd circle
			(at 6.649974 16.150082)
			(size 0.4572 0.4572)
			(layers "F.Cu" "F.Mask" "F.Paste")
			(net "P5E_PEX3_STN1_TX_DP<23>")
		)
		(pad "BB33" smd circle
			(at 7.599934 16.150082)
			(size 0.4572 0.4572)
			(layers "F.Cu" "F.Mask" "F.Paste")
			(net "GND")
		)
		(pad "BB34" smd circle
			(at 8.549894 16.150082)
			(size 0.4572 0.4572)
			(layers "F.Cu" "F.Mask" "F.Paste")
			(net "P5E_PEX3_STN1_TX_DP<25>")
		)
		(pad "BB35" smd circle
			(at 9.500108 16.150082)
			(size 0.4572 0.4572)
			(layers "F.Cu" "F.Mask" "F.Paste")
			(net "GND")
		)
		(pad "BB36" smd circle
			(at 10.450068 16.150082)
			(size 0.4572 0.4572)
			(layers "F.Cu" "F.Mask" "F.Paste")
			(net "P5E_PEX3_STN1_TX_DP<27>")
		)
		(pad "BB37" smd circle
			(at 11.400028 16.150082)
			(size 0.4572 0.4572)
			(layers "F.Cu" "F.Mask" "F.Paste")
			(net "GND")
		)
		(pad "BB38" smd circle
			(at 12.349988 16.150082)
			(size 0.4572 0.4572)
			(layers "F.Cu" "F.Mask" "F.Paste")
			(net "P5E_PEX3_STN1_TX_DP<29>")
		)
		(pad "BB39" smd circle
			(at 13.299948 16.150082)
			(size 0.4572 0.4572)
			(layers "F.Cu" "F.Mask" "F.Paste")
			(net "GND")
		)
		(pad "BB40" smd circle
			(at 14.249908 16.150082)
			(size 0.4572 0.4572)
			(layers "F.Cu" "F.Mask" "F.Paste")
			(net "P5E_PEX3_STN1_TX_DP<31>")
		)
		(pad "BB41" smd circle
			(at 15.200122 16.150082)
			(size 0.4572 0.4572)
			(layers "F.Cu" "F.Mask" "F.Paste")
			(net "GND")
		)
		(pad "BB42" smd circle
			(at 16.150082 16.150082)
			(size 0.4572 0.4572)
			(layers "F.Cu" "F.Mask" "F.Paste")
			(net "P5E_PEX3_STN0_TX_DP<14>")
		)
		(pad "BB43" smd circle
			(at 17.100042 16.150082)
			(size 0.4572 0.4572)
			(layers "F.Cu" "F.Mask" "F.Paste")
			(net "GND")
		)
		(pad "BB44" smd circle
			(at 18.050002 16.150082)
			(size 0.4572 0.4572)
			(layers "F.Cu" "F.Mask" "F.Paste")
			(net "P5E_PEX3_STN0_TX_DP<12>")
		)
		(pad "BB45" smd circle
			(at 18.999962 16.150082)
			(size 0.4572 0.4572)
			(layers "F.Cu" "F.Mask" "F.Paste")
			(net "GND")
		)
		(pad "BB46" smd circle
			(at 19.949922 16.150082)
			(size 0.4572 0.4572)
			(layers "F.Cu" "F.Mask" "F.Paste")
			(net "P5E_PEX3_STN0_TX_DN<10>")
		)
		(pad "BB47" smd circle
			(at 20.899882 16.150082)
			(size 0.4572 0.4572)
			(layers "F.Cu" "F.Mask" "F.Paste")
			(net "GND")
		)
		(pad "BB48" smd circle
			(at 21.850096 16.150082)
			(size 0.4572 0.4572)
			(layers "F.Cu" "F.Mask" "F.Paste")
			(net "P5E_PEX3_STN0_TX_DP<7>")
		)
		(pad "BB49" smd circle
			(at 22.800056 16.150082)
			(size 0.4572 0.4572)
			(layers "F.Cu" "F.Mask" "F.Paste")
			(net "P5E_PEX3_STN0_TX_DN<7>")
		)
		(pad "BC1" smd circle
			(at -22.800056 17.100042)
			(size 0.4572 0.4572)
			(layers "F.Cu" "F.Mask" "F.Paste")
			(net "GND")
		)
		(pad "BC2" smd circle
			(at -21.850096 17.100042)
			(size 0.4572 0.4572)
			(layers "F.Cu" "F.Mask" "F.Paste")
			(net "GND")
		)
		(pad "BC3" smd circle
			(at -20.899882 17.100042)
			(size 0.4572 0.4572)
			(layers "F.Cu" "F.Mask" "F.Paste")
			(net "Net_1428")
		)
		(pad "BC4" smd circle
			(at -19.949922 17.100042)
			(size 0.4572 0.4572)
			(layers "F.Cu" "F.Mask" "F.Paste")
			(net "GND")
		)
		(pad "BC5" smd circle
			(at -18.999962 17.100042)
			(size 0.4572 0.4572)
			(layers "F.Cu" "F.Mask" "F.Paste")
			(net "Net_1452")
		)
		(pad "BC6" smd circle
			(at -18.050002 17.100042)
			(size 0.4572 0.4572)
			(layers "F.Cu" "F.Mask" "F.Paste")
			(net "GND")
		)
		(pad "BC7" smd circle
			(at -17.100042 17.100042)
			(size 0.4572 0.4572)
			(layers "F.Cu" "F.Mask" "F.Paste")
			(net "Net_1466")
		)
		(pad "BC8" smd circle
			(at -16.150082 17.100042)
			(size 0.4572 0.4572)
			(layers "F.Cu" "F.Mask" "F.Paste")
			(net "GND")
		)
		(pad "BC9" smd circle
			(at -15.200122 17.100042)
			(size 0.4572 0.4572)
			(layers "F.Cu" "F.Mask" "F.Paste")
			(net "P5E_PEX3_STN2_TX_DP<47>")
		)
		(pad "BC10" smd circle
			(at -14.249908 17.100042)
			(size 0.4572 0.4572)
			(layers "F.Cu" "F.Mask" "F.Paste")
			(net "GND")
		)
		(pad "BC11" smd circle
			(at -13.299948 17.100042)
			(size 0.4572 0.4572)
			(layers "F.Cu" "F.Mask" "F.Paste")
			(net "P5E_PEX3_STN2_TX_DP<45>")
		)
		(pad "BC12" smd circle
			(at -12.349988 17.100042)
			(size 0.4572 0.4572)
			(layers "F.Cu" "F.Mask" "F.Paste")
			(net "GND")
		)
		(pad "BC13" smd circle
			(at -11.400028 17.100042)
			(size 0.4572 0.4572)
			(layers "F.Cu" "F.Mask" "F.Paste")
			(net "P5E_PEX3_STN2_TX_DP<43>")
		)
		(pad "BC14" smd circle
			(at -10.450068 17.100042)
			(size 0.4572 0.4572)
			(layers "F.Cu" "F.Mask" "F.Paste")
			(net "GND")
		)
		(pad "BC15" smd circle
			(at -9.500108 17.100042)
			(size 0.4572 0.4572)
			(layers "F.Cu" "F.Mask" "F.Paste")
			(net "P5E_PEX3_STN2_TX_DP<41>")
		)
	)
)
